(kicad_pcb
	(version 20260206)
	(generator "pcbnew")
	(generator_version "10.0")
	(general
		(thickness 1.6)
		(legacy_teardrops no)
	)
	(paper "A4")
	(title_block
		(title "04192023_DAF0TMB3IC0_F0TG_MB_C_brd_V02_OCP.brd")
		(comment 1 "Grand Teton / footprints 4642-4648 of 8354")
	)
	(layers
		(0 "F.Cu" signal "TOP")
		(4 "In1.Cu" signal "GND")
		(6 "In2.Cu" signal "IN1")
		(8 "In3.Cu" signal "GND1")
		(10 "In4.Cu" signal "IN2")
		(12 "In5.Cu" signal "GND2")
		(14 "In6.Cu" signal "IN3")
		(16 "In7.Cu" signal "GND3")
		(18 "In8.Cu" signal "VCC")
		(20 "In9.Cu" signal "VCC1")
		(22 "In10.Cu" signal "GND4")
		(24 "In11.Cu" signal "IN4")
		(26 "In12.Cu" signal "GND5")
		(28 "In13.Cu" signal "IN5")
		(30 "In14.Cu" signal "GND6")
		(32 "In15.Cu" signal "IN6")
		(34 "In16.Cu" signal "GND7")
		(2 "B.Cu" signal "BOTTOM")
		(9 "F.Adhes" user "F.Adhesive")
		(11 "B.Adhes" user "B.Adhesive")
		(13 "F.Paste" user "Package Geometry/Pastemask Top")
		(15 "B.Paste" user "Package Geometry/Pastemask Bottom")
		(5 "F.SilkS" user "Ref Des/Silkscreen Top")
		(7 "B.SilkS" user "Ref Des/Silkscreen Bottom")
		(1 "F.Mask" user "Board Geometry/Soldermask Top")
		(3 "B.Mask" user "Board Geometry/Soldermask Bottom")
		(17 "Dwgs.User" user "User.Drawings")
		(19 "Cmts.User" user "User.Comments")
		(21 "Eco1.User" user "User.Eco1")
		(23 "Eco2.User" user "User.Eco2")
		(25 "Edge.Cuts" user "Board Geometry/Outline")
		(27 "Margin" user)
		(31 "F.CrtYd" user "Package Geometry/Place Bound Top")
		(29 "B.CrtYd" user "Package Geometry/Place Bound Bottom")
		(35 "F.Fab" user "Ref Des/Assembly Top")
		(33 "B.Fab" user "Ref Des/Assembly Bottom")
	)
	(footprint ""
		(layer "F.Cu")
		(at 445.003682 -65.947798 -90)
		(property "Reference" "C1332"
			(at 0 0 270)
			(layer "F.SilkS")
			(hide yes)
			(effects
				(font
					(size 1.27 1.27)
				)
			)
		)
		(property "Value" ""
			(at 0 0 270)
			(layer "F.Fab")
			(effects
				(font
					(size 1.27 1.27)
				)
			)
		)
		(duplicate_pad_numbers_are_jumpers no)
		(fp_line
			(start -0.7874 0.4064)
			(end -0.7874 -0.4064)
			(stroke
				(width 0.1524)
				(type default)
			)
			(layer "F.SilkS")
		)
		(fp_line
			(start 0.7874 0.4064)
			(end -0.7874 0.4064)
			(stroke
				(width 0.1524)
				(type default)
			)
			(layer "F.SilkS")
		)
		(fp_line
			(start -0.7874 -0.4064)
			(end 0.7874 -0.4064)
			(stroke
				(width 0.1524)
				(type default)
			)
			(layer "F.SilkS")
		)
		(fp_line
			(start 0.7874 -0.4064)
			(end 0.7874 0.4064)
			(stroke
				(width 0.1524)
				(type default)
			)
			(layer "F.SilkS")
		)
		(fp_line
			(start -0.67945 0.3048)
			(end -0.67945 -0.305054)
			(stroke
				(width 0.1)
				(type default)
			)
			(layer "F.Fab")
		)
		(fp_line
			(start -0.12065 0.3048)
			(end -0.67945 0.3048)
			(stroke
				(width 0.1)
				(type default)
			)
			(layer "F.Fab")
		)
		(fp_line
			(start 0.120396 0.3048)
			(end 0.120396 0.2794)
			(stroke
				(width 0.1)
				(type default)
			)
			(layer "F.Fab")
		)
		(fp_line
			(start 0.67945 0.3048)
			(end 0.120396 0.3048)
			(stroke
				(width 0.1)
				(type default)
			)
			(layer "F.Fab")
		)
		(fp_line
			(start -0.12065 0.2794)
			(end -0.12065 0.3048)
			(stroke
				(width 0.1)
				(type default)
			)
			(layer "F.Fab")
		)
		(fp_line
			(start 0.120396 0.2794)
			(end -0.12065 0.2794)
			(stroke
				(width 0.1)
				(type default)
			)
			(layer "F.Fab")
		)
		(fp_line
			(start -0.12065 -0.2794)
			(end 0.12065 -0.2794)
			(stroke
				(width 0.1)
				(type default)
			)
			(layer "F.Fab")
		)
		(fp_line
			(start 0.12065 -0.2794)
			(end 0.12065 -0.3048)
			(stroke
				(width 0.1)
				(type default)
			)
			(layer "F.Fab")
		)
		(fp_line
			(start 0.12065 -0.3048)
			(end 0.67945 -0.3048)
			(stroke
				(width 0.1)
				(type default)
			)
			(layer "F.Fab")
		)
		(fp_line
			(start 0.67945 -0.3048)
			(end 0.67945 0.3048)
			(stroke
				(width 0.1)
				(type default)
			)
			(layer "F.Fab")
		)
		(fp_line
			(start -0.67945 -0.305054)
			(end -0.12065 -0.305054)
			(stroke
				(width 0.1)
				(type default)
			)
			(layer "F.Fab")
		)
		(fp_line
			(start -0.12065 -0.305054)
			(end -0.12065 -0.2794)
			(stroke
				(width 0.1)
				(type default)
			)
			(layer "F.Fab")
		)
		(pad "1" smd circle
			(at -0.40005 0 270)
			(size 0 0)
			(layers "F.Cu" "F.Mask" "F.Paste")
			(net "P3V3_AUX")
		)
		(pad "2" smd circle
			(at 0.40005 0 270)
			(size 0 0)
			(layers "F.Cu" "F.Mask" "F.Paste")
			(net "GND")
		)
	)
	(footprint ""
		(layer "F.Cu")
		(at 154.633676 -50.739294 90)
		(property "Reference" "R3594"
			(at 0 0 90)
			(layer "F.SilkS")
			(hide yes)
			(effects
				(font
					(size 1.27 1.27)
				)
			)
		)
		(property "Value" ""
			(at 0 0 90)
			(layer "F.Fab")
			(effects
				(font
					(size 1.27 1.27)
				)
			)
		)
		(duplicate_pad_numbers_are_jumpers no)
		(fp_line
			(start 0.7874 -0.4064)
			(end 0.7874 0.4064)
			(stroke
				(width 0.1524)
				(type default)
			)
			(layer "F.SilkS")
		)
		(fp_line
			(start -0.7874 -0.4064)
			(end 0.7874 -0.4064)
			(stroke
				(width 0.1524)
				(type default)
			)
			(layer "F.SilkS")
		)
		(fp_line
			(start 0.7874 0.4064)
			(end -0.7874 0.4064)
			(stroke
				(width 0.1524)
				(type default)
			)
			(layer "F.SilkS")
		)
		(fp_line
			(start -0.7874 0.4064)
			(end -0.7874 -0.4064)
			(stroke
				(width 0.1524)
				(type default)
			)
			(layer "F.SilkS")
		)
		(fp_line
			(start -0.12065 -0.305054)
			(end -0.12065 -0.2794)
			(stroke
				(width 0.1)
				(type default)
			)
			(layer "F.Fab")
		)
		(fp_line
			(start -0.67945 -0.305054)
			(end -0.12065 -0.305054)
			(stroke
				(width 0.1)
				(type default)
			)
			(layer "F.Fab")
		)
		(fp_line
			(start 0.67945 -0.3048)
			(end 0.67945 0.3048)
			(stroke
				(width 0.1)
				(type default)
			)
			(layer "F.Fab")
		)
		(fp_line
			(start 0.12065 -0.3048)
			(end 0.67945 -0.3048)
			(stroke
				(width 0.1)
				(type default)
			)
			(layer "F.Fab")
		)
		(fp_line
			(start 0.12065 -0.2794)
			(end 0.12065 -0.3048)
			(stroke
				(width 0.1)
				(type default)
			)
			(layer "F.Fab")
		)
		(fp_line
			(start -0.12065 -0.2794)
			(end 0.12065 -0.2794)
			(stroke
				(width 0.1)
				(type default)
			)
			(layer "F.Fab")
		)
		(fp_line
			(start 0.120396 0.2794)
			(end -0.12065 0.2794)
			(stroke
				(width 0.1)
				(type default)
			)
			(layer "F.Fab")
		)
		(fp_line
			(start -0.12065 0.2794)
			(end -0.12065 0.3048)
			(stroke
				(width 0.1)
				(type default)
			)
			(layer "F.Fab")
		)
		(fp_line
			(start 0.67945 0.3048)
			(end 0.120396 0.3048)
			(stroke
				(width 0.1)
				(type default)
			)
			(layer "F.Fab")
		)
		(fp_line
			(start 0.120396 0.3048)
			(end 0.120396 0.2794)
			(stroke
				(width 0.1)
				(type default)
			)
			(layer "F.Fab")
		)
		(fp_line
			(start -0.12065 0.3048)
			(end -0.67945 0.3048)
			(stroke
				(width 0.1)
				(type default)
			)
			(layer "F.Fab")
		)
		(fp_line
			(start -0.67945 0.3048)
			(end -0.67945 -0.305054)
			(stroke
				(width 0.1)
				(type default)
			)
			(layer "F.Fab")
		)
		(pad "1" smd circle
			(at -0.40005 0 90)
			(size 0 0)
			(layers "F.Cu" "F.Mask" "F.Paste")
			(net "SMB_INA230_3V3AUX_SCL")
		)
		(pad "2" smd circle
			(at 0.40005 0 90)
			(size 0 0)
			(layers "F.Cu" "F.Mask" "F.Paste")
			(net "SMB_INA230_4_3V3AUX_SCL_R")
		)
	)
	(footprint ""
		(layer "F.Cu")
		(at 304.094896 -383.88163 -90)
		(property "Reference" "C925"
			(at 0 0 270)
			(layer "F.SilkS")
			(hide yes)
			(effects
				(font
					(size 1.27 1.27)
				)
			)
		)
		(property "Value" ""
			(at 0 0 270)
			(layer "F.Fab")
			(effects
				(font
					(size 1.27 1.27)
				)
			)
		)
		(duplicate_pad_numbers_are_jumpers no)
		(fp_line
			(start -0.299974 0.150114)
			(end -0.299974 -0.150114)
			(stroke
				(width 0.1)
				(type default)
			)
			(layer "F.Fab")
		)
		(fp_line
			(start 0.299974 0.150114)
			(end -0.299974 0.150114)
			(stroke
				(width 0.1)
				(type default)
			)
			(layer "F.Fab")
		)
		(fp_line
			(start -0.299974 -0.150114)
			(end 0.299974 -0.150114)
			(stroke
				(width 0.1)
				(type default)
			)
			(layer "F.Fab")
		)
		(fp_line
			(start 0.299974 -0.150114)
			(end 0.299974 0.150114)
			(stroke
				(width 0.1)
				(type default)
			)
			(layer "F.Fab")
		)
		(pad "1" smd rect
			(at -0.2667 0 270)
			(size 0.3048 0.381)
			(layers "F.Cu" "F.Mask" "F.Paste")
			(net "P5E_CPU0_P0_TX_C_DP<4>")
		)
		(pad "2" smd rect
			(at 0.2667 0 270)
			(size 0.3048 0.381)
			(layers "F.Cu" "F.Mask" "F.Paste")
			(net "P5E_CPU0_P0_TX_DP<4>")
		)
	)
	(footprint ""
		(layer "F.Cu")
		(at 160.274762 -111.221774 180)
		(property "Reference" "R6116"
			(at 0 0 180)
			(layer "F.SilkS")
			(hide yes)
			(effects
				(font
					(size 1.27 1.27)
				)
			)
		)
		(property "Value" ""
			(at 0 0 180)
			(layer "F.Fab")
			(effects
				(font
					(size 1.27 1.27)
				)
			)
		)
		(duplicate_pad_numbers_are_jumpers no)
		(fp_line
			(start 0.7874 0.4064)
			(end -0.7874 0.4064)
			(stroke
				(width 0.1524)
				(type default)
			)
			(layer "F.SilkS")
		)
		(fp_line
			(start 0.7874 -0.4064)
			(end 0.7874 0.4064)
			(stroke
				(width 0.1524)
				(type default)
			)
			(layer "F.SilkS")
		)
		(fp_line
			(start -0.7874 0.4064)
			(end -0.7874 -0.4064)
			(stroke
				(width 0.1524)
				(type default)
			)
			(layer "F.SilkS")
		)
		(fp_line
			(start -0.7874 -0.4064)
			(end 0.7874 -0.4064)
			(stroke
				(width 0.1524)
				(type default)
			)
			(layer "F.SilkS")
		)
		(fp_line
			(start 0.67945 0.3048)
			(end 0.120396 0.3048)
			(stroke
				(width 0.1)
				(type default)
			)
			(layer "F.Fab")
		)
		(fp_line
			(start 0.67945 -0.3048)
			(end 0.67945 0.3048)
			(stroke
				(width 0.1)
				(type default)
			)
			(layer "F.Fab")
		)
		(fp_line
			(start 0.12065 -0.2794)
			(end 0.12065 -0.3048)
			(stroke
				(width 0.1)
				(type default)
			)
			(layer "F.Fab")
		)
		(fp_line
			(start 0.12065 -0.3048)
			(end 0.67945 -0.3048)
			(stroke
				(width 0.1)
				(type default)
			)
			(layer "F.Fab")
		)
		(fp_line
			(start 0.120396 0.3048)
			(end 0.120396 0.2794)
			(stroke
				(width 0.1)
				(type default)
			)
			(layer "F.Fab")
		)
		(fp_line
			(start 0.120396 0.2794)
			(end -0.12065 0.2794)
			(stroke
				(width 0.1)
				(type default)
			)
			(layer "F.Fab")
		)
		(fp_line
			(start -0.12065 0.3048)
			(end -0.67945 0.3048)
			(stroke
				(width 0.1)
				(type default)
			)
			(layer "F.Fab")
		)
		(fp_line
			(start -0.12065 0.2794)
			(end -0.12065 0.3048)
			(stroke
				(width 0.1)
				(type default)
			)
			(layer "F.Fab")
		)
		(fp_line
			(start -0.12065 -0.2794)
			(end 0.12065 -0.2794)
			(stroke
				(width 0.1)
				(type default)
			)
			(layer "F.Fab")
		)
		(fp_line
			(start -0.12065 -0.305054)
			(end -0.12065 -0.2794)
			(stroke
				(width 0.1)
				(type default)
			)
			(layer "F.Fab")
		)
		(fp_line
			(start -0.67945 0.3048)
			(end -0.67945 -0.305054)
			(stroke
				(width 0.1)
				(type default)
			)
			(layer "F.Fab")
		)
		(fp_line
			(start -0.67945 -0.305054)
			(end -0.12065 -0.305054)
			(stroke
				(width 0.1)
				(type default)
			)
			(layer "F.Fab")
		)
		(pad "1" smd circle
			(at -0.40005 0 180)
			(size 0 0)
			(layers "F.Cu" "F.Mask" "F.Paste")
			(net "E1S_0_PERST1_CLKREQ_R_N")
		)
		(pad "2" smd circle
			(at 0.40005 0 180)
			(size 0 0)
			(layers "F.Cu" "F.Mask" "F.Paste")
			(net "E1S_0_PRSNT_N")
		)
	)
	(footprint ""
		(layer "F.Cu")
		(at 146.939 -120.777)
		(property "Reference" "R8086"
			(at 0 0 0)
			(layer "F.SilkS")
			(hide yes)
			(effects
				(font
					(size 1.27 1.27)
				)
			)
		)
		(property "Value" ""
			(at 0 0 0)
			(layer "F.Fab")
			(effects
				(font
					(size 1.27 1.27)
				)
			)
		)
		(duplicate_pad_numbers_are_jumpers no)
		(fp_line
			(start -0.7874 -0.4064)
			(end 0.7874 -0.4064)
			(stroke
				(width 0.1524)
				(type default)
			)
			(layer "F.SilkS")
		)
		(fp_line
			(start -0.7874 0.4064)
			(end -0.7874 -0.4064)
			(stroke
				(width 0.1524)
				(type default)
			)
			(layer "F.SilkS")
		)
		(fp_line
			(start 0.7874 -0.4064)
			(end 0.7874 0.4064)
			(stroke
				(width 0.1524)
				(type default)
			)
			(layer "F.SilkS")
		)
		(fp_line
			(start 0.7874 0.4064)
			(end -0.7874 0.4064)
			(stroke
				(width 0.1524)
				(type default)
			)
			(layer "F.SilkS")
		)
		(fp_line
			(start -0.67945 -0.305054)
			(end -0.12065 -0.305054)
			(stroke
				(width 0.1)
				(type default)
			)
			(layer "F.Fab")
		)
		(fp_line
			(start -0.67945 0.3048)
			(end -0.67945 -0.305054)
			(stroke
				(width 0.1)
				(type default)
			)
			(layer "F.Fab")
		)
		(fp_line
			(start -0.12065 -0.305054)
			(end -0.12065 -0.2794)
			(stroke
				(width 0.1)
				(type default)
			)
			(layer "F.Fab")
		)
		(fp_line
			(start -0.12065 -0.2794)
			(end 0.12065 -0.2794)
			(stroke
				(width 0.1)
				(type default)
			)
			(layer "F.Fab")
		)
		(fp_line
			(start -0.12065 0.2794)
			(end -0.12065 0.3048)
			(stroke
				(width 0.1)
				(type default)
			)
			(layer "F.Fab")
		)
		(fp_line
			(start -0.12065 0.3048)
			(end -0.67945 0.3048)
			(stroke
				(width 0.1)
				(type default)
			)
			(layer "F.Fab")
		)
		(fp_line
			(start 0.120396 0.2794)
			(end -0.12065 0.2794)
			(stroke
				(width 0.1)
				(type default)
			)
			(layer "F.Fab")
		)
		(fp_line
			(start 0.120396 0.3048)
			(end 0.120396 0.2794)
			(stroke
				(width 0.1)
				(type default)
			)
			(layer "F.Fab")
		)
		(fp_line
			(start 0.12065 -0.3048)
			(end 0.67945 -0.3048)
			(stroke
				(width 0.1)
				(type default)
			)
			(layer "F.Fab")
		)
		(fp_line
			(start 0.12065 -0.2794)
			(end 0.12065 -0.3048)
			(stroke
				(width 0.1)
				(type default)
			)
			(layer "F.Fab")
		)
		(fp_line
			(start 0.67945 -0.3048)
			(end 0.67945 0.3048)
			(stroke
				(width 0.1)
				(type default)
			)
			(layer "F.Fab")
		)
		(fp_line
			(start 0.67945 0.3048)
			(end 0.120396 0.3048)
			(stroke
				(width 0.1)
				(type default)
			)
			(layer "F.Fab")
		)
		(pad "1" smd circle
			(at -0.40005 0)
			(size 0 0)
			(layers "F.Cu" "F.Mask" "F.Paste")
			(net "PWRGD_CHAF_CPU1")
		)
		(pad "2" smd circle
			(at 0.40005 0)
			(size 0 0)
			(layers "F.Cu" "F.Mask" "F.Paste")
			(net "PWRGD_CHAF_CPU1_R1")
		)
	)
	(footprint ""
		(layer "F.Cu")
		(at 103.505 -418.973 180)
		(property "Reference" "R3492"
			(at 0 0 180)
			(layer "F.SilkS")
			(hide yes)
			(effects
				(font
					(size 1.27 1.27)
				)
			)
		)
		(property "Value" ""
			(at 0 0 180)
			(layer "F.Fab")
			(effects
				(font
					(size 1.27 1.27)
				)
			)
		)
		(duplicate_pad_numbers_are_jumpers no)
		(fp_line
			(start 0.7874 0.4064)
			(end -0.7874 0.4064)
			(stroke
				(width 0.1524)
				(type default)
			)
			(layer "F.SilkS")
		)
		(fp_line
			(start 0.7874 -0.4064)
			(end 0.7874 0.4064)
			(stroke
				(width 0.1524)
				(type default)
			)
			(layer "F.SilkS")
		)
		(fp_line
			(start -0.7874 0.4064)
			(end -0.7874 -0.4064)
			(stroke
				(width 0.1524)
				(type default)
			)
			(layer "F.SilkS")
		)
		(fp_line
			(start -0.7874 -0.4064)
			(end 0.7874 -0.4064)
			(stroke
				(width 0.1524)
				(type default)
			)
			(layer "F.SilkS")
		)
		(fp_line
			(start 0.67945 0.3048)
			(end 0.120396 0.3048)
			(stroke
				(width 0.1)
				(type default)
			)
			(layer "F.Fab")
		)
		(fp_line
			(start 0.67945 -0.3048)
			(end 0.67945 0.3048)
			(stroke
				(width 0.1)
				(type default)
			)
			(layer "F.Fab")
		)
		(fp_line
			(start 0.12065 -0.2794)
			(end 0.12065 -0.3048)
			(stroke
				(width 0.1)
				(type default)
			)
			(layer "F.Fab")
		)
		(fp_line
			(start 0.12065 -0.3048)
			(end 0.67945 -0.3048)
			(stroke
				(width 0.1)
				(type default)
			)
			(layer "F.Fab")
		)
		(fp_line
			(start 0.120396 0.3048)
			(end 0.120396 0.2794)
			(stroke
				(width 0.1)
				(type default)
			)
			(layer "F.Fab")
		)
		(fp_line
			(start 0.120396 0.2794)
			(end -0.12065 0.2794)
			(stroke
				(width 0.1)
				(type default)
			)
			(layer "F.Fab")
		)
		(fp_line
			(start -0.12065 0.3048)
			(end -0.67945 0.3048)
			(stroke
				(width 0.1)
				(type default)
			)
			(layer "F.Fab")
		)
		(fp_line
			(start -0.12065 0.2794)
			(end -0.12065 0.3048)
			(stroke
				(width 0.1)
				(type default)
			)
			(layer "F.Fab")
		)
		(fp_line
			(start -0.12065 -0.2794)
			(end 0.12065 -0.2794)
			(stroke
				(width 0.1)
				(type default)
			)
			(layer "F.Fab")
		)
		(fp_line
			(start -0.12065 -0.305054)
			(end -0.12065 -0.2794)
			(stroke
				(width 0.1)
				(type default)
			)
			(layer "F.Fab")
		)
		(fp_line
			(start -0.67945 0.3048)
			(end -0.67945 -0.305054)
			(stroke
				(width 0.1)
				(type default)
			)
			(layer "F.Fab")
		)
		(fp_line
			(start -0.67945 -0.305054)
			(end -0.12065 -0.305054)
			(stroke
				(width 0.1)
				(type default)
			)
			(layer "F.Fab")
		)
		(pad "1" smd circle
			(at -0.40005 0 180)
			(size 0 0)
			(layers "F.Cu" "F.Mask" "F.Paste")
			(net "P3V3_AUX")
		)
		(pad "2" smd circle
			(at 0.40005 0 180)
			(size 0 0)
			(layers "F.Cu" "F.Mask" "F.Paste")
			(net "GPU_FPGA_EROT_RST_BUF_R_N")
		)
	)
	(footprint ""
		(layer "F.Cu")
		(at 397.125952 -323.45503)
		(property "Reference" "R1504"
			(at 0 0 0)
			(layer "F.SilkS")
			(hide yes)
			(effects
				(font
					(size 1.27 1.27)
				)
			)
		)
		(property "Value" ""
			(at 0 0 0)
			(layer "F.Fab")
			(effects
				(font
					(size 1.27 1.27)
				)
			)
		)
		(duplicate_pad_numbers_are_jumpers no)
		(fp_line
			(start -0.7874 -0.4064)
			(end 0.7874 -0.4064)
			(stroke
				(width 0.1524)
				(type default)
			)
			(layer "F.SilkS")
		)
		(fp_line
			(start -0.7874 0.4064)
			(end -0.7874 -0.4064)
			(stroke
				(width 0.1524)
				(type default)
			)
			(layer "F.SilkS")
		)
		(fp_line
			(start 0.7874 -0.4064)
			(end 0.7874 0.4064)
			(stroke
				(width 0.1524)
				(type default)
			)
			(layer "F.SilkS")
		)
		(fp_line
			(start 0.7874 0.4064)
			(end -0.7874 0.4064)
			(stroke
				(width 0.1524)
				(type default)
			)
			(layer "F.SilkS")
		)
		(fp_line
			(start -0.67945 -0.305054)
			(end -0.12065 -0.305054)
			(stroke
				(width 0.1)
				(type default)
			)
			(layer "F.Fab")
		)
		(fp_line
			(start -0.67945 0.3048)
			(end -0.67945 -0.305054)
			(stroke
				(width 0.1)
				(type default)
			)
			(layer "F.Fab")
		)
		(fp_line
			(start -0.12065 -0.305054)
			(end -0.12065 -0.2794)
			(stroke
				(width 0.1)
				(type default)
			)
			(layer "F.Fab")
		)
		(fp_line
			(start -0.12065 -0.2794)
			(end 0.12065 -0.2794)
			(stroke
				(width 0.1)
				(type default)
			)
			(layer "F.Fab")
		)
		(fp_line
			(start -0.12065 0.2794)
			(end -0.12065 0.3048)
			(stroke
				(width 0.1)
				(type default)
			)
			(layer "F.Fab")
		)
		(fp_line
			(start -0.12065 0.3048)
			(end -0.67945 0.3048)
			(stroke
				(width 0.1)
				(type default)
			)
			(layer "F.Fab")
		)
		(fp_line
			(start 0.120396 0.2794)
			(end -0.12065 0.2794)
			(stroke
				(width 0.1)
				(type default)
			)
			(layer "F.Fab")
		)
		(fp_line
			(start 0.120396 0.3048)
			(end 0.120396 0.2794)
			(stroke
				(width 0.1)
				(type default)
			)
			(layer "F.Fab")
		)
		(fp_line
			(start 0.12065 -0.3048)
			(end 0.67945 -0.3048)
			(stroke
				(width 0.1)
				(type default)
			)
			(layer "F.Fab")
		)
		(fp_line
			(start 0.12065 -0.2794)
			(end 0.12065 -0.3048)
			(stroke
				(width 0.1)
				(type default)
			)
			(layer "F.Fab")
		)
		(fp_line
			(start 0.67945 -0.3048)
			(end 0.67945 0.3048)
			(stroke
				(width 0.1)
				(type default)
			)
			(layer "F.Fab")
		)
		(fp_line
			(start 0.67945 0.3048)
			(end 0.120396 0.3048)
			(stroke
				(width 0.1)
				(type default)
			)
			(layer "F.Fab")
		)
		(pad "1" smd circle
			(at -0.40005 0)
			(size 0 0)
			(layers "F.Cu" "F.Mask" "F.Paste")
			(net "PVDD18_S5_P0")
		)
		(pad "2" smd circle
			(at 0.40005 0)
			(size 0 0)
			(layers "F.Cu" "F.Mask" "F.Paste")
			(net "ESPI_CPU0_D1")
		)
	)
)
